# BASEBOARD_FAB2 (Tioga Pass) — schematic netlist excerpt (pin names and nets, part order shuffled) for the footprints in the layout excerpt that follows; sources: Cadence DE-HDL packaged netlist, KiCad conversion of Wiwynn_Tioga_Pass_MB.brd

C25W18  SC1U16V3KX-2GP  10%  pkg SMD-BCG  page 151 : \1\ = P1V2_AUX_BMC ; \2\ = GND
C10W5  CAP_A  0.01UF 25V 10% X7R  pkg 0402V  page 251 : A = PUMP_TACH1 ; B = GND
R3D15  RES  49.9 1% CHIP  pkg 0402  page 96 : A = PVCCIO_CPU1 ; B = PWRGD_CPU1_G

(kicad_pcb
	(version 20260206)
	(generator "pcbnew")
	(generator_version "10.0")
	(general
		(thickness 1.6)
		(legacy_teardrops no)
	)
	(paper "A4")
	(title_block
		(title "Wiwynn_Tioga_Pass_MB.brd")
		(comment 1 "Tioga Pass / footprints 1807-1809 of 4770")
	)
	(layers
		(0 "F.Cu" signal "TOP")
		(4 "In1.Cu" signal "L2GND")
		(6 "In2.Cu" signal "L3")
		(8 "In3.Cu" signal "L4GND")
		(10 "In4.Cu" signal "L5")
		(12 "In5.Cu" signal "L6GND")
		(14 "In6.Cu" signal "L7VCC")
		(16 "In7.Cu" signal "L8VCC")
		(18 "In8.Cu" signal "L9GND")
		(20 "In9.Cu" signal "L10")
		(22 "In10.Cu" signal "L11GND")
		(24 "In11.Cu" signal "L12")
		(26 "In12.Cu" signal "L13GND")
		(2 "B.Cu" signal "BOTTOM")
		(9 "F.Adhes" user "F.Adhesive")
		(11 "B.Adhes" user "B.Adhesive")
		(13 "F.Paste" user "Package Geometry/Pastemask Top")
		(15 "B.Paste" user "Package Geometry/Pastemask Bottom")
		(5 "F.SilkS" user "Ref Des/Silkscreen Top")
		(7 "B.SilkS" user "Ref Des/Silkscreen Bottom")
		(1 "F.Mask" user "Board Geometry/Soldermask Top")
		(3 "B.Mask" user "Board Geometry/Soldermask Bottom")
		(17 "Dwgs.User" user "User.Drawings")
		(19 "Cmts.User" user "User.Comments")
		(21 "Eco1.User" user "User.Eco1")
		(23 "Eco2.User" user "User.Eco2")
		(25 "Edge.Cuts" user "Board Geometry/Outline")
		(27 "Margin" user)
		(31 "F.CrtYd" user "Package Geometry/Place Bound Top")
		(29 "B.CrtYd" user "Package Geometry/Place Bound Bottom")
		(35 "F.Fab" user "Ref Des/Assembly Top")
		(33 "B.Fab" user "Ref Des/Assembly Bottom")
	)
	(footprint ""
		(layer "F.Cu")
		(at 442.368686 -43.254676)
		(property "Reference" "C25W18"
			(at 0 0 0)
			(layer "F.SilkS")
			(hide yes)
			(effects
				(font
					(size 1.27 1.27)
				)
			)
		)
		(property "Value" "*"
			(at 0 -2.9337 0)
			(unlocked yes)
			(layer "F.Fab")
			(hide yes)
			(effects
				(font
					(size 1.27 1.016)
					(thickness 0.1524)
				)
			)
		)
		(property "Device Type" "SC1U16V3KX-2GP_SMD-BCG-SC1U16VA"
			(at 0 -4.4577 0)
			(unlocked yes)
			(layer "F.Fab")
			(hide yes)
			(effects
				(font
					(size 1.27 1.016)
					(thickness 0.1524)
				)
			)
		)
		(duplicate_pad_numbers_are_jumpers no)
		(fp_line
			(start 0.508 0)
			(end -0.508 0)
			(stroke
				(width 0.2032)
				(type default)
			)
			(layer "F.SilkS")
		)
		(fp_rect
			(start -0.5842 1.3335)
			(end 0.5842 -1.3335)
			(stroke
				(width 0)
				(type default)
			)
			(fill no)
			(layer "F.CrtYd")
		)
		(fp_rect
			(start -0.5842 1.3335)
			(end 0.5842 -1.3335)
			(stroke
				(width 0)
				(type default)
			)
			(fill no)
			(layer "F.Fab")
		)
		(pad "1" smd custom
			(at 0 -0.762)
			(size 0.2159 0.2159)
			(layers "F.Cu" "F.Mask" "F.Paste")
			(net "P1V2_AUX_BMC")
			(options
				(clearance outline)
				(anchor circle)
			)
			(primitives
				(gr_poly
					(pts
						(arc
							(start -0.3302 -0.4318)
							(mid -0.402042 -0.402042)
							(end -0.4318 -0.3302)
						)
						(arc
							(start -0.4318 0.3302)
							(mid -0.402042 0.402042)
							(end -0.3302 0.4318)
						)
						(arc
							(start 0.3302 0.4318)
							(mid 0.402042 0.402042)
							(end 0.4318 0.3302)
						)
						(arc
							(start 0.4318 -0.3302)
							(mid 0.402042 -0.402042)
							(end 0.3302 -0.4318)
						)
					)
					(width 0)
					(fill yes)
				)
			)
		)
		(pad "2" smd custom
			(at 0 0.762)
			(size 0.2159 0.2159)
			(layers "F.Cu" "F.Mask" "F.Paste")
			(net "GND")
			(options
				(clearance outline)
				(anchor circle)
			)
			(primitives
				(gr_poly
					(pts
						(arc
							(start -0.3302 -0.4318)
							(mid -0.402042 -0.402042)
							(end -0.4318 -0.3302)
						)
						(arc
							(start -0.4318 0.3302)
							(mid -0.402042 0.402042)
							(end -0.3302 0.4318)
						)
						(arc
							(start 0.3302 0.4318)
							(mid 0.402042 0.402042)
							(end 0.4318 0.3302)
						)
						(arc
							(start 0.4318 -0.3302)
							(mid 0.402042 -0.402042)
							(end 0.3302 -0.4318)
						)
					)
					(width 0)
					(fill yes)
				)
			)
		)
	)
	(footprint ""
		(layer "F.Cu")
		(at -0.277622 -118.636034 90)
		(property "Reference" "C10W5"
			(at -0.8382 -0.67818 90)
			(unlocked yes)
			(layer "F.SilkS")
			(effects
				(font
					(size 0.4064 0.254)
					(thickness 0.1524)
				)
				(justify left)
			)
		)
		(property "Value" ""
			(at 0 0 90)
			(layer "F.Fab")
			(effects
				(font
					(size 1.27 1.27)
				)
			)
		)
		(duplicate_pad_numbers_are_jumpers no)
		(fp_poly
			(pts
				(xy 0.3048 -0.1016) (xy 0.3048 0.9906) (xy -0.3048 0.9906) (xy -0.3048 -0.1016)
			)
			(stroke
				(width 0)
				(type default)
			)
			(fill no)
			(layer "F.CrtYd")
		)
		(fp_line
			(start 0.3048 -0.1016)
			(end -0.3048 -0.1016)
			(stroke
				(width 0.1)
				(type default)
			)
			(layer "F.Fab")
		)
		(fp_line
			(start -0.3048 -0.1016)
			(end -0.3048 0.9906)
			(stroke
				(width 0.1)
				(type default)
			)
			(layer "F.Fab")
		)
		(fp_line
			(start 0.3048 0.9906)
			(end 0.3048 -0.1016)
			(stroke
				(width 0.1)
				(type default)
			)
			(layer "F.Fab")
		)
		(fp_line
			(start -0.3048 0.9906)
			(end 0.3048 0.9906)
			(stroke
				(width 0.1)
				(type default)
			)
			(layer "F.Fab")
		)
		(pad "1" smd rect
			(at 0 0 90)
			(size 0.508 0.508)
			(layers "F.Cu" "F.Mask" "F.Paste")
			(net "PUMP_TACH1")
		)
		(pad "2" smd rect
			(at 0 0.889 90)
			(size 0.508 0.508)
			(layers "F.Cu" "F.Mask" "F.Paste")
			(net "GND")
		)
		(zone
			(layer "F.Cu")
			(hatch none 0.5)
			(connect_pads
				(clearance 0)
			)
			(min_thickness 0.25)
			(keepout
				(tracks allowed)
				(vias not_allowed)
				(pads allowed)
				(copperpour not_allowed)
				(footprints allowed)
			)
			(placement
				(enabled no)
				(sheetname "")
			)
			(fill
				(thermal_gap 0.5)
				(thermal_bridge_width 0.5)
				(island_removal_mode 0)
			)
			(polygon
				(pts
					(xy -0.023622 -118.382034) (xy -0.023622 -118.890034) (xy 0.357378 -118.890034) (xy 0.357378 -118.382034)
				)
			)
		)
		(zone
			(layer "F.Cu")
			(hatch none 0.5)
			(connect_pads
				(clearance 0)
			)
			(min_thickness 0.25)
			(keepout
				(tracks not_allowed)
				(vias allowed)
				(pads allowed)
				(copperpour not_allowed)
				(footprints allowed)
			)
			(placement
				(enabled no)
				(sheetname "")
			)
			(fill
				(thermal_gap 0.5)
				(thermal_bridge_width 0.5)
				(island_removal_mode 0)
			)
			(polygon
				(pts
					(xy 0.357378 -118.382034) (xy 0.357378 -118.890034) (xy -0.023622 -118.890034) (xy -0.023622 -118.382034)
				)
			)
		)
	)
	(footprint ""
		(layer "F.Cu")
		(at 116.3066 -73.787 90)
		(property "Reference" "R3D15"
			(at 0 0 90)
			(layer "F.SilkS")
			(hide yes)
			(effects
				(font
					(size 1.27 1.27)
				)
			)
		)
		(property "Value" ""
			(at 0 0 90)
			(layer "F.Fab")
			(effects
				(font
					(size 1.27 1.27)
				)
			)
		)
		(duplicate_pad_numbers_are_jumpers no)
		(fp_poly
			(pts
				(xy -0.2794 -0.1016) (xy 0.2794 -0.1016) (xy 0.2794 0.9906) (xy -0.2794 0.9906)
			)
			(stroke
				(width 0)
				(type default)
			)
			(fill no)
			(layer "F.CrtYd")
		)
		(fp_line
			(start 0.2794 -0.1016)
			(end -0.2794 -0.1016)
			(stroke
				(width 0.1)
				(type default)
			)
			(layer "F.Fab")
		)
		(fp_line
			(start -0.2794 -0.1016)
			(end -0.2794 0.9906)
			(stroke
				(width 0.1)
				(type default)
			)
			(layer "F.Fab")
		)
		(fp_line
			(start 0.2794 0.9906)
			(end 0.2794 -0.1016)
			(stroke
				(width 0.1)
				(type default)
			)
			(layer "F.Fab")
		)
		(fp_line
			(start -0.2794 0.9906)
			(end 0.2794 0.9906)
			(stroke
				(width 0.1)
				(type default)
			)
			(layer "F.Fab")
		)
		(pad "1" smd rect
			(at 0 0 90)
			(size 0.508 0.508)
			(layers "F.Cu" "F.Mask" "F.Paste")
			(net "PVCCIO_CPU1")
		)
		(pad "2" smd rect
			(at 0 0.889 90)
			(size 0.508 0.508)
			(layers "F.Cu" "F.Mask" "F.Paste")
			(net "PWRGD_CPU1_G")
		)
		(zone
			(layer "F.Cu")
			(hatch none 0.5)
			(connect_pads
				(clearance 0)
			)
			(min_thickness 0.25)
			(keepout
				(tracks allowed)
				(vias not_allowed)
				(pads allowed)
				(copperpour not_allowed)
				(footprints allowed)
			)
			(placement
				(enabled no)
				(sheetname "")
			)
			(fill
				(thermal_gap 0.5)
				(thermal_bridge_width 0.5)
				(island_removal_mode 0)
			)
			(polygon
				(pts
					(xy 116.5606 -73.533) (xy 116.5606 -74.041) (xy 116.9416 -74.041) (xy 116.9416 -73.533)
				)
			)
		)
		(zone
			(layer "F.Cu")
			(hatch none 0.5)
			(connect_pads
				(clearance 0)
			)
			(min_thickness 0.25)
			(keepout
				(tracks not_allowed)
				(vias allowed)
				(pads allowed)
				(copperpour not_allowed)
				(footprints allowed)
			)
			(placement
				(enabled no)
				(sheetname "")
			)
			(fill
				(thermal_gap 0.5)
				(thermal_bridge_width 0.5)
				(island_removal_mode 0)
			)
			(polygon
				(pts
					(xy 116.9416 -73.533) (xy 116.9416 -74.041) (xy 116.5606 -74.041) (xy 116.5606 -73.533)
				)
			)
		)
	)
)
